# T6G (Grand Teton) — schematic netlist excerpt (pin names and nets, part order shuffled) for the footprints in the layout excerpt that follows; sources: Cadence DE-HDL packaged netlist, KiCad conversion of 04192023_DAF0TMB3IC0_F0TG_MB_C_brd_V02_OCP.brd

R170  Q_RES  33 5% CHIP  pkg 0402LF  page 80 : A = FM_I3C_CPU1_MUX0_R_SEL ; B = FM_I3C_CPU1_MUX0_SEL

PL20  Q_INDUCTOR4P_14  150NH IND  pkg L_TLM117513Q-151QL_11X7-5XA  page 206
  \1\  = SW_PVDDIO_P0_SW4
  \2\  = IND_PVDDIO_P0_CPL0
  \3\  = IND_PVDDIO_P0_CPL4
  \4\  = PVDDIO_P0

(kicad_pcb
	(version 20260206)
	(generator "pcbnew")
	(generator_version "10.0")
	(general
		(thickness 1.6)
		(legacy_teardrops no)
	)
	(paper "A4")
	(title_block
		(title "04192023_DAF0TMB3IC0_F0TG_MB_C_brd_V02_OCP.brd")
		(comment 1 "Grand Teton / footprints 3557-3558 of 8354")
	)
	(layers
		(0 "F.Cu" signal "TOP")
		(4 "In1.Cu" signal "GND")
		(6 "In2.Cu" signal "IN1")
		(8 "In3.Cu" signal "GND1")
		(10 "In4.Cu" signal "IN2")
		(12 "In5.Cu" signal "GND2")
		(14 "In6.Cu" signal "IN3")
		(16 "In7.Cu" signal "GND3")
		(18 "In8.Cu" signal "VCC")
		(20 "In9.Cu" signal "VCC1")
		(22 "In10.Cu" signal "GND4")
		(24 "In11.Cu" signal "IN4")
		(26 "In12.Cu" signal "GND5")
		(28 "In13.Cu" signal "IN5")
		(30 "In14.Cu" signal "GND6")
		(32 "In15.Cu" signal "IN6")
		(34 "In16.Cu" signal "GND7")
		(2 "B.Cu" signal "BOTTOM")
		(9 "F.Adhes" user "F.Adhesive")
		(11 "B.Adhes" user "B.Adhesive")
		(13 "F.Paste" user "Package Geometry/Pastemask Top")
		(15 "B.Paste" user "Package Geometry/Pastemask Bottom")
		(5 "F.SilkS" user "Ref Des/Silkscreen Top")
		(7 "B.SilkS" user "Ref Des/Silkscreen Bottom")
		(1 "F.Mask" user "Board Geometry/Soldermask Top")
		(3 "B.Mask" user "Board Geometry/Soldermask Bottom")
		(17 "Dwgs.User" user "User.Drawings")
		(19 "Cmts.User" user "User.Comments")
		(21 "Eco1.User" user "User.Eco1")
		(23 "Eco2.User" user "User.Eco2")
		(25 "Edge.Cuts" user "Board Geometry/Outline")
		(27 "Margin" user)
		(31 "F.CrtYd" user "Package Geometry/Place Bound Top")
		(29 "B.CrtYd" user "Package Geometry/Place Bound Bottom")
		(35 "F.Fab" user "Ref Des/Assembly Top")
		(33 "B.Fab" user "Ref Des/Assembly Bottom")
	)
	(footprint ""
		(layer "F.Cu")
		(at 275.539962 -337.399122)
		(property "Reference" "PL20"
			(at -1.854962 -15.888208 0)
			(unlocked yes)
			(layer "F.SilkS")
			(effects
				(font
					(size 0.7874 0.5842)
					(thickness 0.1524)
				)
				(justify left)
			)
		)
		(property "Value" ""
			(at 0 0 0)
			(layer "F.Fab")
			(effects
				(font
					(size 1.27 1.27)
				)
			)
		)
		(duplicate_pad_numbers_are_jumpers no)
		(fp_line
			(start -3.750056 -5.500116)
			(end -2.393442 -5.500116)
			(stroke
				(width 0.1524)
				(type default)
			)
			(layer "F.SilkS")
		)
		(fp_line
			(start -3.750056 5.500116)
			(end -3.750056 -5.500116)
			(stroke
				(width 0.1524)
				(type default)
			)
			(layer "F.SilkS")
		)
		(fp_line
			(start -2.393442 5.500116)
			(end -3.750056 5.500116)
			(stroke
				(width 0.1524)
				(type default)
			)
			(layer "F.SilkS")
		)
		(fp_line
			(start 2.393442 5.500116)
			(end 3.750056 5.500116)
			(stroke
				(width 0.1524)
				(type default)
			)
			(layer "F.SilkS")
		)
		(fp_line
			(start 3.750056 -5.500116)
			(end 2.393442 -5.500116)
			(stroke
				(width 0.1524)
				(type default)
			)
			(layer "F.SilkS")
		)
		(fp_line
			(start 3.750056 5.500116)
			(end 3.750056 -5.500116)
			(stroke
				(width 0.1524)
				(type default)
			)
			(layer "F.SilkS")
		)
		(fp_poly
			(pts
				(xy -3.965448 -5.22478) (xy -4.42341 -5.377434) (xy -4.118102 -5.682742)
			)
			(stroke
				(width 0)
				(type default)
			)
			(fill yes)
			(layer "F.SilkS")
		)
		(fp_line
			(start -3.750056 -5.500116)
			(end -3.750056 5.500116)
			(stroke
				(width 0.1)
				(type default)
			)
			(layer "F.Fab")
		)
		(fp_line
			(start -3.750056 5.500116)
			(end 3.750056 5.500116)
			(stroke
				(width 0.1)
				(type default)
			)
			(layer "F.Fab")
		)
		(fp_line
			(start 3.750056 -5.500116)
			(end -3.750056 -5.500116)
			(stroke
				(width 0.1)
				(type default)
			)
			(layer "F.Fab")
		)
		(fp_line
			(start 3.750056 5.500116)
			(end 3.750056 -5.500116)
			(stroke
				(width 0.1)
				(type default)
			)
			(layer "F.Fab")
		)
		(fp_poly
			(pts
				(xy -4.9276 -4.757928) (xy -4.9276 -3.741928) (xy -3.9116 -4.249928)
			)
			(stroke
				(width 0)
				(type default)
			)
			(fill yes)
			(layer "F.Fab")
		)
		(pad "1" smd rect
			(at 0 -4.249928 270)
			(size 2.413 4.5212)
			(layers "F.Cu" "F.Mask" "F.Paste")
			(net "SW_PVDDIO_P0_SW4")
		)
		(pad "2" smd rect
			(at 0 -1.175004 270)
			(size 1.3716 4.5212)
			(layers "F.Cu" "F.Mask" "F.Paste")
			(net "IND_PVDDIO_P0_CPL0")
		)
		(pad "3" smd rect
			(at 0 1.175004 270)
			(size 1.3716 4.5212)
			(layers "F.Cu" "F.Mask" "F.Paste")
			(net "IND_PVDDIO_P0_CPL4")
		)
		(pad "4" smd rect
			(at 0 4.249928 270)
			(size 2.413 4.5212)
			(layers "F.Cu" "F.Mask" "F.Paste")
			(net "PVDDIO_P0")
		)
	)
	(footprint ""
		(layer "F.Cu")
		(at 171.196 -107.152948 180)
		(property "Reference" "R170"
			(at 0 0 180)
			(layer "F.SilkS")
			(hide yes)
			(effects
				(font
					(size 1.27 1.27)
				)
			)
		)
		(property "Value" ""
			(at 0 0 180)
			(layer "F.Fab")
			(effects
				(font
					(size 1.27 1.27)
				)
			)
		)
		(duplicate_pad_numbers_are_jumpers no)
		(fp_line
			(start 0.7874 0.4064)
			(end -0.7874 0.4064)
			(stroke
				(width 0.1524)
				(type default)
			)
			(layer "F.SilkS")
		)
		(fp_line
			(start 0.7874 -0.4064)
			(end 0.7874 0.4064)
			(stroke
				(width 0.1524)
				(type default)
			)
			(layer "F.SilkS")
		)
		(fp_line
			(start -0.7874 0.4064)
			(end -0.7874 -0.4064)
			(stroke
				(width 0.1524)
				(type default)
			)
			(layer "F.SilkS")
		)
		(fp_line
			(start -0.7874 -0.4064)
			(end 0.7874 -0.4064)
			(stroke
				(width 0.1524)
				(type default)
			)
			(layer "F.SilkS")
		)
		(fp_line
			(start 0.67945 0.3048)
			(end 0.120396 0.3048)
			(stroke
				(width 0.1)
				(type default)
			)
			(layer "F.Fab")
		)
		(fp_line
			(start 0.67945 -0.3048)
			(end 0.67945 0.3048)
			(stroke
				(width 0.1)
				(type default)
			)
			(layer "F.Fab")
		)
		(fp_line
			(start 0.12065 -0.2794)
			(end 0.12065 -0.3048)
			(stroke
				(width 0.1)
				(type default)
			)
			(layer "F.Fab")
		)
		(fp_line
			(start 0.12065 -0.3048)
			(end 0.67945 -0.3048)
			(stroke
				(width 0.1)
				(type default)
			)
			(layer "F.Fab")
		)
		(fp_line
			(start 0.120396 0.3048)
			(end 0.120396 0.2794)
			(stroke
				(width 0.1)
				(type default)
			)
			(layer "F.Fab")
		)
		(fp_line
			(start 0.120396 0.2794)
			(end -0.12065 0.2794)
			(stroke
				(width 0.1)
				(type default)
			)
			(layer "F.Fab")
		)
		(fp_line
			(start -0.12065 0.3048)
			(end -0.67945 0.3048)
			(stroke
				(width 0.1)
				(type default)
			)
			(layer "F.Fab")
		)
		(fp_line
			(start -0.12065 0.2794)
			(end -0.12065 0.3048)
			(stroke
				(width 0.1)
				(type default)
			)
			(layer "F.Fab")
		)
		(fp_line
			(start -0.12065 -0.2794)
			(end 0.12065 -0.2794)
			(stroke
				(width 0.1)
				(type default)
			)
			(layer "F.Fab")
		)
		(fp_line
			(start -0.12065 -0.305054)
			(end -0.12065 -0.2794)
			(stroke
				(width 0.1)
				(type default)
			)
			(layer "F.Fab")
		)
		(fp_line
			(start -0.67945 0.3048)
			(end -0.67945 -0.305054)
			(stroke
				(width 0.1)
				(type default)
			)
			(layer "F.Fab")
		)
		(fp_line
			(start -0.67945 -0.305054)
			(end -0.12065 -0.305054)
			(stroke
				(width 0.1)
				(type default)
			)
			(layer "F.Fab")
		)
		(pad "1" smd circle
			(at -0.40005 0 180)
			(size 0 0)
			(layers "F.Cu" "F.Mask" "F.Paste")
			(net "FM_I3C_CPU1_MUX0_R_SEL")
		)
		(pad "2" smd circle
			(at 0.40005 0 180)
			(size 0 0)
			(layers "F.Cu" "F.Mask" "F.Paste")
			(net "FM_I3C_CPU1_MUX0_SEL")
		)
	)
)
